(kicad_pcb
	(version 20240108)
	(generator "pcbnew")
	(generator_version "8.0")
	(general
		(thickness 1.586)
		(legacy_teardrops no)
	)
	(paper "A4")
	(title_block
		(title "GMSL Serializer")
		(date "2024-11-27")
		(rev "1.1.1")
		(company "Antmicro Ltd")
		(comment 1 "www.antmicro.com")
		(comment 9 "footprint 4 of 117 (U6), pads 1-33 of 33")
	)
	(layers
		(0 "F.Cu" signal)
		(1 "In1.Cu" power)
		(2 "In2.Cu" power)
		(31 "B.Cu" signal)
		(32 "B.Adhes" user "B.Adhesive")
		(33 "F.Adhes" user "F.Adhesive")
		(34 "B.Paste" user)
		(35 "F.Paste" user)
		(36 "B.SilkS" user "B.Silkscreen")
		(37 "F.SilkS" user "F.Silkscreen")
		(38 "B.Mask" user)
		(39 "F.Mask" user)
		(40 "Dwgs.User" user "User.Drawings")
		(41 "Cmts.User" user "User.Comments")
		(42 "Eco1.User" user "User.Eco1")
		(43 "Eco2.User" user "User.Eco2")
		(44 "Edge.Cuts" user)
		(45 "Margin" user)
		(46 "B.CrtYd" user "B.Courtyard")
		(47 "F.CrtYd" user "F.Courtyard")
		(48 "B.Fab" user)
		(49 "F.Fab" user)
	)
	(footprint "antmicro-footprints:TQFN-32-1EP_5x5mm_P0.5mm"
		(layer "F.Cu")
		(at 147.65 101.85 135)
		(property "Reference" "U6"
			(at -1.704127 -3.768879 -45)
			(unlocked yes)
			(layer "F.SilkS")
			(effects
				(font
					(size 0.7 0.7)
					(thickness 0.15)
				)
				(justify left bottom)
			)
		)
		(property "Value" "MAX96717GTJ_VY+"
			(at -3.05 4 135)
			(unlocked yes)
			(layer "F.Fab")
			(effects
				(font
					(size 0.7 0.7)
					(thickness 0.15)
				)
				(justify left bottom)
			)
		)
		(property "Footprint" "antmicro-footprints:TQFN-32-1EP_5x5mm_P0.5mm"
			(at 0 0 135)
			(layer "F.Fab")
			(hide yes)
			(effects
				(font
					(size 1.27 1.27)
					(thickness 0.15)
				)
			)
		)
		(property "Datasheet" "https://www.analog.com/media/en/technical-documentation/data-sheets/max96717.pdf"
			(at 0 0 135)
			(layer "F.Fab")
			(hide yes)
			(effects
				(font
					(size 1.27 1.27)
					(thickness 0.15)
				)
			)
		)
		(property "Author" "Antmicro"
			(at 324.073142 69.464509 0)
			(layer "F.Fab")
			(hide yes)
			(effects
				(font
					(size 1 1)
					(thickness 0.15)
				)
			)
		)
		(property "License" "Apache-2.0"
			(at 324.073142 69.464509 0)
			(layer "F.Fab")
			(hide yes)
			(effects
				(font
					(size 1 1)
					(thickness 0.15)
				)
			)
		)
		(property "MPN" "MAX96717GTJ/VY+"
			(at 324.073142 69.464509 0)
			(layer "F.Fab")
			(hide yes)
			(effects
				(font
					(size 1 1)
					(thickness 0.15)
				)
			)
		)
		(property "Manufacturer" "Analog Devices"
			(at 324.073142 69.464509 0)
			(layer "F.Fab")
			(hide yes)
			(effects
				(font
					(size 1 1)
					(thickness 0.15)
				)
			)
		)
		(sheetname "Serializer")
		(sheetfile "serializer.kicad_sch")
		(attr smd)
		(pad "1" smd roundrect
			(at -2.4 -1.75 225)
			(size 0.254 0.8128)
			(layers "F.Cu" "F.Paste" "F.Mask")
			(roundrect_rratio 0.25)
			(net 77 "Net-(U6-PWDNB)")
			(pinfunction "PWDNB")
			(pintype "input")
		)
		(pad "2" smd roundrect
			(at -2.4 -1.25 225)
			(size 0.254 0.8128)
			(layers "F.Cu" "F.Paste" "F.Mask")
			(roundrect_rratio 0.25)
			(net 83 "Net-(U6-MFP0)")
			(pinfunction "MFP0")
			(pintype "bidirectional")
		)
		(pad "3" smd roundrect
			(at -2.4 -0.75 225)
			(size 0.254 0.8128)
			(layers "F.Cu" "F.Paste" "F.Mask")
			(roundrect_rratio 0.25)
			(net 66 "/Serializer/CFG0")
			(pinfunction "MFP1")
			(pintype "bidirectional")
		)
		(pad "4" smd roundrect
			(at -2.4 -0.25 225)
			(size 0.254 0.8128)
			(layers "F.Cu" "F.Paste" "F.Mask")
			(roundrect_rratio 0.25)
			(net 68 "/Serializer/CFG1")
			(pinfunction "MFP2")
			(pintype "bidirectional")
		)
		(pad "5" smd roundrect
			(at -2.4 0.25 225)
			(size 0.254 0.8128)
			(layers "F.Cu" "F.Paste" "F.Mask")
			(roundrect_rratio 0.25)
			(net 81 "Net-(U6-MFP9)")
			(pinfunction "MFP9")
			(pintype "bidirectional")
		)
		(pad "6" smd roundrect
			(at -2.4 0.75 225)
			(size 0.254 0.8128)
			(layers "F.Cu" "F.Paste" "F.Mask")
			(roundrect_rratio 0.25)
			(net 82 "Net-(U6-MFP10)")
			(pinfunction "MFP10")
			(pintype "bidirectional")
		)
		(pad "7" smd roundrect
			(at -2.4 1.25 225)
			(size 0.254 0.8128)
			(layers "F.Cu" "F.Paste" "F.Mask")
			(roundrect_rratio 0.25)
			(net 90 "/Serializer/VREF")
			(pinfunction "VREF")
			(pintype "power_in")
		)
		(pad "8" smd roundrect
			(at -2.4 1.75 225)
			(size 0.254 0.8128)
			(layers "F.Cu" "F.Paste" "F.Mask")
			(roundrect_rratio 0.25)
			(net 13 "/Serializer/X1")
			(pinfunction "X1/OSC")
			(pintype "bidirectional")
		)
		(pad "9" smd roundrect
			(at -1.75 2.4 135)
			(size 0.254 0.8128)
			(layers "F.Cu" "F.Paste" "F.Mask")
			(roundrect_rratio 0.25)
			(net 67 "/Serializer/X2")
			(pinfunction "X2")
			(pintype "bidirectional")
		)
		(pad "10" smd roundrect
			(at -1.25 2.4 135)
			(size 0.254 0.8128)
			(layers "F.Cu" "F.Paste" "F.Mask")
			(roundrect_rratio 0.25)
			(net 76 "Net-(U6-XRES)")
			(pinfunction "XRES")
			(pintype "passive")
		)
		(pad "11" smd roundrect
			(at -0.75 2.4 135)
			(size 0.254 0.8128)
			(layers "F.Cu" "F.Paste" "F.Mask")
			(roundrect_rratio 0.25)
			(net 11 "+1V8")
			(pinfunction "VDD18")
			(pintype "power_in")
		)
		(pad "12" smd roundrect
			(at -0.25 2.4 135)
			(size 0.254 0.8128)
			(layers "F.Cu" "F.Paste" "F.Mask")
			(roundrect_rratio 0.25)
			(net 17 "Net-(U6-SIOP)")
			(pinfunction "SIOP")
			(pintype "bidirectional")
		)
		(pad "13" smd roundrect
			(at 0.25 2.4 135)
			(size 0.254 0.8128)
			(layers "F.Cu" "F.Paste" "F.Mask")
			(roundrect_rratio 0.25)
			(net 33 "Net-(U6-SION)")
			(pinfunction "SION")
			(pintype "bidirectional")
		)
		(pad "14" smd roundrect
			(at 0.75 2.4 135)
			(size 0.254 0.8128)
			(layers "F.Cu" "F.Paste" "F.Mask")
			(roundrect_rratio 0.25)
			(net 15 "Net-(U6-CAP_VDD)")
			(pinfunction "CAP_VDD")
			(pintype "power_in")
		)
		(pad "15" smd roundrect
			(at 1.25 2.4 135)
			(size 0.254 0.8128)
			(layers "F.Cu" "F.Paste" "F.Mask")
			(roundrect_rratio 0.25)
			(net 12 "+1V2")
			(pinfunction "VDD")
			(pintype "power_in")
		)
		(pad "16" smd roundrect
			(at 1.75 2.4 135)
			(size 0.254 0.8128)
			(layers "F.Cu" "F.Paste" "F.Mask")
			(roundrect_rratio 0.25)
			(net 10 "+3V3")
			(pinfunction "VDDIO")
			(pintype "power_in")
		)
		(pad "17" smd roundrect
			(at 2.4 1.75 225)
			(size 0.254 0.8128)
			(layers "F.Cu" "F.Paste" "F.Mask")
			(roundrect_rratio 0.25)
			(net 38 "/CSI Connector/GPIO3")
			(pinfunction "MFP3")
			(pintype "bidirectional")
		)
		(pad "18" smd roundrect
			(at 2.4 1.25 225)
			(size 0.254 0.8128)
			(layers "F.Cu" "F.Paste" "F.Mask")
			(roundrect_rratio 0.25)
			(net 87 "/CSI Connector/GPIO4")
			(pinfunction "MFP4")
			(pintype "bidirectional")
		)
		(pad "19" smd roundrect
			(at 2.4 0.75 225)
			(size 0.254 0.8128)
			(layers "F.Cu" "F.Paste" "F.Mask")
			(roundrect_rratio 0.25)
			(net 44 "/CSI Connector/CSI.D2_P")
			(pinfunction "D2P")
			(pintype "input")
		)
		(pad "20" smd roundrect
			(at 2.4 0.25 225)
			(size 0.254 0.8128)
			(layers "F.Cu" "F.Paste" "F.Mask")
			(roundrect_rratio 0.25)
			(net 42 "/CSI Connector/CSI.D2_N")
			(pinfunction "D2N")
			(pintype "input")
		)
		(pad "21" smd roundrect
			(at 2.4 -0.25 225)
			(size 0.254 0.8128)
			(layers "F.Cu" "F.Paste" "F.Mask")
			(roundrect_rratio 0.25)
			(net 84 "Net-(U6-MFP5)")
			(pinfunction "MFP5")
			(pintype "bidirectional")
		)
		(pad "22" smd roundrect
			(at 2.4 -0.75 225)
			(size 0.254 0.8128)
			(layers "F.Cu" "F.Paste" "F.Mask")
			(roundrect_rratio 0.25)
			(net 85 "Net-(U6-MFP6)")
			(pinfunction "MFP6")
			(pintype "bidirectional")
		)
		(pad "23" smd roundrect
			(at 2.4 -1.25 225)
			(size 0.254 0.8128)
			(layers "F.Cu" "F.Paste" "F.Mask")
			(roundrect_rratio 0.25)
			(net 41 "/CSI Connector/CSI.D3_P")
			(pinfunction "D3P")
			(pintype "input")
		)
		(pad "24" smd roundrect
			(at 2.4 -1.75 225)
			(size 0.254 0.8128)
			(layers "F.Cu" "F.Paste" "F.Mask")
			(roundrect_rratio 0.25)
			(net 40 "/CSI Connector/CSI.D3_N")
			(pinfunction "D3N")
			(pintype "input")
		)
		(pad "25" smd roundrect
			(at 1.75 -2.4 135)
			(size 0.254 0.8128)
			(layers "F.Cu" "F.Paste" "F.Mask")
			(roundrect_rratio 0.25)
			(net 57 "/CSI Connector/CSI.D0_P")
			(pinfunction "D0P")
			(pintype "input")
		)
		(pad "26" smd roundrect
			(at 1.25 -2.4 135)
			(size 0.254 0.8128)
			(layers "F.Cu" "F.Paste" "F.Mask")
			(roundrect_rratio 0.25)
			(net 56 "/CSI Connector/CSI.D0_N")
			(pinfunction "D0N")
			(pintype "input")
		)
		(pad "27" smd roundrect
			(at 0.75 -2.4 135)
			(size 0.254 0.8128)
			(layers "F.Cu" "F.Paste" "F.Mask")
			(roundrect_rratio 0.25)
			(net 80 "/CSI Connector/CSI.CLK_P")
			(pinfunction "CKP")
			(pintype "input")
		)
		(pad "28" smd roundrect
			(at 0.25 -2.4 135)
			(size 0.254 0.8128)
			(layers "F.Cu" "F.Paste" "F.Mask")
			(roundrect_rratio 0.25)
			(net 61 "/CSI Connector/CSI.CLK_N")
			(pinfunction "CKN")
			(pintype "input")
		)
		(pad "29" smd roundrect
			(at -0.25 -2.4 135)
			(size 0.254 0.8128)
			(layers "F.Cu" "F.Paste" "F.Mask")
			(roundrect_rratio 0.25)
			(net 51 "/CSI Connector/CSI.D1_P")
			(pinfunction "D1P")
			(pintype "input")
		)
		(pad "30" smd roundrect
			(at -0.75 -2.4 135)
			(size 0.254 0.8128)
			(layers "F.Cu" "F.Paste" "F.Mask")
			(roundrect_rratio 0.25)
			(net 50 "/CSI Connector/CSI.D1_N")
			(pinfunction "D1N")
			(pintype "input")
		)
		(pad "31" smd roundrect
			(at -1.25 -2.4 135)
			(size 0.254 0.8128)
			(layers "F.Cu" "F.Paste" "F.Mask")
			(roundrect_rratio 0.25)
			(net 78 "Net-(U6-MFP7)")
			(pinfunction "MFP7")
			(pintype "bidirectional")
		)
		(pad "32" smd roundrect
			(at -1.75 -2.4 135)
			(size 0.254 0.8128)
			(layers "F.Cu" "F.Paste" "F.Mask")
			(roundrect_rratio 0.25)
			(net 79 "Net-(U6-MFP8)")
			(pinfunction "MFP8")
			(pintype "bidirectional")
		)
		(pad "33" smd rect
			(at 0 0 135)
			(size 3.15 3.15)
			(layers "F.Cu" "F.Paste" "F.Mask")
			(net 1 "GND")
			(pinfunction "GND")
			(pintype "power_in")
		)
	)
)
